# SCM (Grand Teton) — schematic netlist excerpt (pin names and nets, part order shuffled) for the footprints in the layout excerpt that follows; sources: Cadence DE-HDL packaged netlist, KiCad conversion of 12092022_DA0F0TMDCD0_F0T_Management_Board_D_brd_V3_OCP.brd

U25  LCMXO3LF2100C5BG256C  LCMXO3LF-2100C-5BG256C IC  pkg BGA256_0-8_14X14  page 34
  VCC_A1  = PVCCA_AUX_PLD
  NC1  = NC
  PT11C  = BSM_PRSNT_R1_N
  PT10A  = RST_PLTRST_R1_N
  PT11A  = RST_RSMRST_N
  \pt12d||tdi\  = JTAG_SCM_PLD_TDI
  \pt16c||tck\  = JTAG_SCM_PLD_TCK
  \pt17b||pclkc0_1\  = IRQ_BMC_PCH_NMI_R_N
  \pt18c||scl||pclkt0_0\  = SMB_BMC_MM16_R3_SCL
  PT19B  = NC
  PT21A  = RST_EXTRST_R_N
  PT22B  = FM_ADR_COMPLETE
  \pt24c||initn\  = PU_FPGA_NSTATUS
  PT22D  = SGPIO_CLK_PLD_0
  PT24B  = FM_THERMTRIP_DLY_LVC1_R_N
  VCC_A16  = PVCCA_AUX_PLD
  PL1C  = NC
  GND_B2  = GND
  PT9C  = IRQ_BMC_CPU_NMI_R
  PT11D  = RST_PCA9548_SENSOR_N
  PT9B  = FM_TPM_PRSNT_1_R_N
  PT11B  = FM_JTAG_BMC_MUX_SEL_R2
  PT13A  = IRQ_UV_DETECT_N
  \pt16d||tms\  = JTAG_SCM_PLD_TMS
  PT19A  = IRQ_PCH_SCI_WHEA_N
  \pt20d||programn\  = PU_PT20D
  PT22A  = IRQ_OC_DETECT_N
  PT23B  = SGPIO_PLD_LD_0
  PT22C  = IRQ_OC_DETECT_EN_N
  PT24A  = SGPIO_PLD_DI_0
  GND_B15  = GND
  PR1D  = FM_PECI_SEL_N
  PL2C  = NC
  PL1D  = NC
  GND_C3  = GND
  PT9A  = FM_TPM_PRSNT_0_R_N
  PT10B  = PWRGD_PSU_AC_PWROK_PLD
  \pt12c||tdo\  = JTAG_SCM_PLD_TDO
  PT13B  = RST_BMC_RSTBTN_OUT_N
  \pt17a||pclkt0_1\  = CLK_25M_OSC_FPGA
  \pt18d||sda||pclkc0_0\  = SMB_BMC_MM16_R3_SDA
  \pt20c||jtagenb\  = JTAG_SCM_PLD_R_JTAGEN
  PT21B  = PWRGD_CPUPWRGD_LVC1
  PT23A  = SGPIO_PLD_DO_0
  \pt24d||done\  = PU_FPGA_CONFIG_DONE
  GND_C14  = GND
  PR1C  = VOL_SEN_ALERT_R
  PR2C  = SMB_BMC_ALERT3_R1_N
  \pl1b||l_gpllc_fb\  = NC
  PL2D  = NC
  \pl1a||l_gpllt_fb\  = NC
  GND_D4  = GND
  VCCIO0_D5  = VCCIO0
  PT12A  = FM_BMC_DBP_PRESENT_N
  PT13D  = FM_ME_BT_DONE
  PT17C  = FM_PCH_BMC_THERMTRIP_N
  PT18B  = NC
  PT20A  = NC
  PT21D  = IRQ_CPU1_VRHOT_N
  VCCIO0_D12  = VCCIO0
  GND_D13  = GND
  PR1A  = H_CPU0_MEMTRIP_LVC1_N
  PR2D  = SMB_BMC_ALERT4_R1_N
  PR2A  = H_CPU1_MEMTRIP_LVC1_N
  \pl3a||pclkt5_0\  = NC
  \pl2a||l_gpllt_in\  = NC
  \pl2b||l_gpllc_in\  = NC
  VCCIO5  = VCCIO5
  GND_E5  = GND
  PT13C  = BMC_CPLD_GPIO_2_R2
  PT12B  = PWRGD_PCH_PWROK
  PT16B  = FM_BIOS_POST_CMPLT_BMC_N
  PT17D  = H_CPU1_PROCHOT_LVC1_R_N
  PT20B  = FM_CPU_MSMI_CATERR_LVT3_PLD_N
  PT19D  = TP_PLD_19D
  GND_E12  = GND
  VCCIO1_E13  = VCCIO1
  PR2B  = IRQ_SGPIO_R_N
  PR1B  = FM_SPD_REMOTE_EN_R
  PR3A  = RST_SGPIO_RESET_R_N
  PL4B  = NC
  \pl3b||pclkc5_0\  = NC
  PL4A  = NC
  PL3C  = NC
  PL5C  = NC
  GND_F6  = GND
  PT16A  = FM_PCIE_M2_SSD0_PRSNT_N
  PT18A  = RST_SRST_PLD_BMC_R2_N
  PT19C  = NC
  PT21C  = IRQ_CPU0_VRHOT_N
  GND_F11  = GND
  PR4C  = TP_PLD_L3
  PR3C  = SMB_BMC_ALERT9_R1_N
  PR4A  = BMC_CPLD_GPIO_8_R2
  PR3B  = BMC_CPLD_GPIO_7_R2
  PR4B  = NC
  PL6A  = NC
  PL5A  = NC
  PL5B  = NC
  PL4D  = NC
  PL4C  = NC
  PL3D  = NC
  VCC_G7  = PVCCA_AUX_PLD
  VCCIO0_G8  = VCCIO0
  VCCIO0_G9  = VCCIO0
  VCC_G10  = PVCCA_AUX_PLD
  PR5C  = FM_SLPS3_GF_R_N
  PR3D  = SMB_BMC_ALERT10_R1_N
  PR4D  = RST_BMC_SELF_HW_R2
  PR5B  = NC
  PR5A  = NC
  PR6A  = BMC_CPLD_GPIO_12_R2
  PL7B  = NC
  PL6B  = NC
  PL7A  = NC
  PL6C  = NC
  PL9C  = NC
  PL5D  = NC
  VCCIO4_H7  = VCCIO4
  GND_H8  = GND
  GND_H9  = GND
  VCCIO1_H10  = VCCIO1
  PR9C  = RST_MB_STBY_R_N
  PR5D  = RST_ROT_CPU_R_N
  PR6C  = FM_ESPI_PLD_R_EN
  \pr7a||pclkt1_0\  = NC
  PR6B  = BMC_CPLD_GPIO_13_R2
  \pr7b||pclkc1_0\  = NC
  \pl7c||pclkt4_0\  = NC
  PL9A  = NC
  \pl7d||pclkc4_0\  = NC
  PL9D  = NC
  PL10C  = NC
  PL6D  = NC
  VCCIO4_J7  = VCCIO4
  GND_J8  = GND
  GND_J9  = GND
  VCCIO1_J10  = VCCIO1
  PR10C  = NC
  PR6D  = FM_THROTTLE_R_N
  PR9D  = FM_ADR_TRIGGER_N
  PR7D  = H_CPU0_PROCHOT_LVC1_R_N
  PR9A  = RST_BMC_HW_R
  PR7C  = FM_PMBUS_ALERT_EN
  PL9B  = NC
  PL10B  = NC
  PL10A  = NC
  PL11C  = NC
  PL12C  = NC
  PL10D  = NC
  VCC_K7  = PVCCA_AUX_PLD
  VCCIO2_K8  = VCCIO2
  VCCIO2_K9  = VCCIO2
  VCC_K10  = PVCCA_AUX_PLD
  PR12C  = FM_PCHHOT_R_N
  PR11D  = FM_BIOS_DEBUG_EN_N
  PR11C  = FM_BMC_READY_PLD_N
  PR10A  = FM_PWR_R_BTN
  PR10B  = PWRGD_SYS_PWROK_PLD
  PR9B  = NC
  PL11A  = NC
  \pl12a||pclkt3_0\  = NC
  PL11B  = NC
  PL12D  = NC
  PL11D  = NC
  GND_L6  = GND
  PB8D  = NC_FM_PFR_NO_SERVICE_ACT_N
  PB11D  = FM_PFR_DSW_PWROK_N
  PB12D  = FM_BMC_CPU_FBRK_OUT_R_N
  PB18D  = FM_UARTSW_MSB_R_N
  GND_L11  = GND
  PR10D  = FM_BMC_EN_DET_R
  PR12D  = FM_BMC_ONCTL_R_N
  PR11B  = SMB_BMC_ALERT12_N
  PR12A  = NC
  PR11A  = USB_OC0_REAR_R_N
  \pl12b||pclkc3_0\  = NC
  PL14A  = NC
  PL13A  = NC
  VCCIO3  = VCCIO3
  GND_M5  = GND
  PB11C  = BMC_MONITER
  PB9C  = CLK_GEN2_BMC_RC_OE_N
  PB16C  = PWRGD_P1V8_AUX_R1
  PB18C  = FM_UARTSW_LSB_R_N
  PB21C  = PU_FPGA_NCONFIG
  PB19D  = NC
  GND_M12  = GND
  VCCIO1_M13  = VCCIO1
  PR13A  = PWR_LED_CPLD
  PR13B  = PWRGD_P5V_AUX_R1
  PR12B  = NC
  PL13B  = NC
  PL13C  = NC
  PL14B  = NC
  GND_N4  = GND
  VCCIO2_N5  = VCCIO2
  PB8C  = FM_BMC_DEBUG_SW_R2_N
  PB9D  = IRQ_SML0_ALERT_R_N
  PB12C  = CLK_BUF1_GPU_FPGA_OE_R_N
  PB16D  = PWRGD_P3V3_RGM_R1
  PB19C  = NC
  PB21D  = NC
  VCCIO2_N12  = VCCIO2
  GND_N13  = GND
  PR14B  = PWRGD_P2V5_AUX_R1
  PR13C  = AC_PWR_BTN_R2_N
  PR14A  = PWRGD_P3V3_AUX_R1
  PL13D  = NC
  PL14D  = NC
  GND_P3  = GND
  PB3A  = FM_P12V_HSC_ENABLE_R2
  PB5B  = TP_PLD_C13
  \pb8a||mclk||cclk\  = FM_HDD_LED_N
  PB9B  = GPU_WP_HW_CTRL_R_N
  PB12A  = GPU_FPGA_RST_N
  \pb16b||pclkc2_1\  = PWRGD_P1V0_AUX_R1
  PB19A  = NC
  PB21B  = NC
  PB24A  = NC
  \pb25b||si||sispi\  = NC
  GND_P14  = GND
  PR14C  = NC
  PR13D  = NC
  PL14C  = NC
  GND_R2  = GND
  PB3D  = PWRGD_DSW_PWROK_R2
  PB6D  = FM_BMC_SUSACK_R2_N
  \pb5a||csspin\  = FM_DEBUG_PORT_R2_PRSNT_N
  PB6B  = FM_BMC_CRASHLOG_TRIG_R2_N
  PB9A  = GPU_NVS_PWR_BRAKE_R_N
  \pb11b||pclkc2_0\  = NC_FM_PFR_UPDATE_N
  PB18A  = NC
  PB19B  = NC
  PB22A  = NC
  \pb25a||sn\  = PU_PB25A
  PB22C  = NC
  PB25D  = SMB_BMC_MM16_R4_SDA
  GND_R15  = GND
  PR14D  = SMB_BMC_ALERT16_R2_N
  VCC_T1  = PVCCA_AUX_PLD
  PB3C  = FM_SOL_UART_CH_SEL_R2
  PB6C  = RST_WDTRST_PLD_R2_N
  PB3B  = NC
  PB6A  = IRQ_PCH_TPM_SPI_R2_N
  \pb8b||so||spiso\  = FM_PCH_BEEP_LED
  \pb11a||pclkt2_0\  = RST_PFR_OVR_RTC_R
  PB12B  = FM_JTAG_TCK_MUX_BMC_SEL
  \pb16a||pclkt2_1\  = PWRGD_P1V2_AUX_R1
  PB18B  = NC
  PB21A  = NC
  PB22B  = NC
  PB24B  = NC
  PB22D  = NC
  PB25C  = SMB_BMC_MM16_R4_SCL
  VCC_T16  = PVCCA_AUX_PLD

(kicad_pcb
	(version 20260206)
	(generator "pcbnew")
	(generator_version "10.0")
	(general
		(thickness 1.6)
		(legacy_teardrops no)
	)
	(paper "A4")
	(title_block
		(title "12092022_DA0F0TMDCD0_F0T_Management_Board_D_brd_V3_OCP.brd")
		(comment 1 "Grand Teton / footprint 162 of 1440 (U25), pads 46-92 of 256")
	)
	(layers
		(0 "F.Cu" signal "TOP")
		(4 "In1.Cu" signal "GND")
		(6 "In2.Cu" signal "IN1")
		(8 "In3.Cu" signal "GND1")
		(10 "In4.Cu" signal "IN2")
		(12 "In5.Cu" signal "VCC")
		(14 "In6.Cu" signal "VCC1")
		(16 "In7.Cu" signal "IN3")
		(18 "In8.Cu" signal "GND2")
		(20 "In9.Cu" signal "IN4")
		(22 "In10.Cu" signal "GND3")
		(2 "B.Cu" signal "BOTTOM")
		(9 "F.Adhes" user "F.Adhesive")
		(11 "B.Adhes" user "B.Adhesive")
		(13 "F.Paste" user "Package Geometry/Pastemask Top")
		(15 "B.Paste" user "Package Geometry/Pastemask Bottom")
		(5 "F.SilkS" user "Ref Des/Silkscreen Top")
		(7 "B.SilkS" user "Ref Des/Silkscreen Bottom")
		(1 "F.Mask" user "Board Geometry/Soldermask Top")
		(3 "B.Mask" user "Board Geometry/Soldermask Bottom")
		(17 "Dwgs.User" user "User.Drawings")
		(19 "Cmts.User" user "User.Comments")
		(21 "Eco1.User" user "User.Eco1")
		(23 "Eco2.User" user "User.Eco2")
		(25 "Edge.Cuts" user "Board Geometry/Outline")
		(27 "Margin" user)
		(31 "F.CrtYd" user "Package Geometry/Place Bound Top")
		(29 "B.CrtYd" user "Package Geometry/Place Bound Bottom")
		(35 "F.Fab" user "Ref Des/Assembly Top")
		(33 "B.Fab" user "Ref Des/Assembly Bottom")
	)
	(footprint ""
		(layer "F.Cu")
		(at 21.459444 -93.587062 180)
		(property "Reference" "U25"
			(at -10.595356 -8.218932 0)
			(unlocked yes)
			(layer "F.SilkS")
			(effects
				(font
					(size 0.7874 0.5842)
					(thickness 0.1524)
				)
				(justify left)
			)
		)
		(property "Value" ""
			(at 0 0 180)
			(layer "F.Fab")
			(effects
				(font
					(size 1.27 1.27)
				)
			)
		)
		(duplicate_pad_numbers_are_jumpers no)
		(pad "C14" smd circle
			(at 4.400042 -4.400042 180)
			(size 0.4064 0.4064)
			(layers "F.Cu" "F.Mask" "F.Paste")
			(net "GND")
		)
		(pad "C15" smd circle
			(at 5.199888 -4.400042 180)
			(size 0.4064 0.4064)
			(layers "F.Cu" "F.Mask" "F.Paste")
			(net "VOL_SEN_ALERT_R")
		)
		(pad "C16" smd circle
			(at 5.999988 -4.400042 180)
			(size 0.4064 0.4064)
			(layers "F.Cu" "F.Mask" "F.Paste")
			(net "SMB_BMC_ALERT3_R1_N")
		)
		(pad "D1" smd circle
			(at -5.999988 -3.599942 180)
			(size 0.4064 0.4064)
			(layers "F.Cu" "F.Mask" "F.Paste")
			(net "Net_297")
		)
		(pad "D2" smd circle
			(at -5.199888 -3.599942 180)
			(size 0.4064 0.4064)
			(layers "F.Cu" "F.Mask" "F.Paste")
			(net "Net_303")
		)
		(pad "D3" smd circle
			(at -4.400042 -3.599942 180)
			(size 0.4064 0.4064)
			(layers "F.Cu" "F.Mask" "F.Paste")
			(net "Net_296")
		)
		(pad "D4" smd circle
			(at -3.599942 -3.599942 180)
			(size 0.4064 0.4064)
			(layers "F.Cu" "F.Mask" "F.Paste")
			(net "GND")
		)
		(pad "D5" smd circle
			(at -2.800096 -3.599942 180)
			(size 0.4064 0.4064)
			(layers "F.Cu" "F.Mask" "F.Paste")
			(net "VCCIO0")
		)
		(pad "D6" smd circle
			(at -1.999996 -3.599942 180)
			(size 0.4064 0.4064)
			(layers "F.Cu" "F.Mask" "F.Paste")
			(net "FM_BMC_DBP_PRESENT_N")
		)
		(pad "D7" smd circle
			(at -1.199896 -3.599942 180)
			(size 0.4064 0.4064)
			(layers "F.Cu" "F.Mask" "F.Paste")
			(net "FM_ME_BT_DONE")
		)
		(pad "D8" smd circle
			(at -0.40005 -3.599942 180)
			(size 0.4064 0.4064)
			(layers "F.Cu" "F.Mask" "F.Paste")
			(net "FM_PCH_BMC_THERMTRIP_N")
		)
		(pad "D9" smd circle
			(at 0.40005 -3.599942 180)
			(size 0.4064 0.4064)
			(layers "F.Cu" "F.Mask" "F.Paste")
			(net "Net_246")
		)
		(pad "D10" smd circle
			(at 1.199896 -3.599942 180)
			(size 0.4064 0.4064)
			(layers "F.Cu" "F.Mask" "F.Paste")
			(net "Net_11")
		)
		(pad "D11" smd circle
			(at 1.999996 -3.599942 180)
			(size 0.4064 0.4064)
			(layers "F.Cu" "F.Mask" "F.Paste")
			(net "IRQ_CPU1_VRHOT_N")
		)
		(pad "D12" smd circle
			(at 2.800096 -3.599942 180)
			(size 0.4064 0.4064)
			(layers "F.Cu" "F.Mask" "F.Paste")
			(net "VCCIO0")
		)
		(pad "D13" smd circle
			(at 3.599942 -3.599942 180)
			(size 0.4064 0.4064)
			(layers "F.Cu" "F.Mask" "F.Paste")
			(net "GND")
		)
		(pad "D14" smd circle
			(at 4.400042 -3.599942 180)
			(size 0.4064 0.4064)
			(layers "F.Cu" "F.Mask" "F.Paste")
			(net "H_CPU0_MEMTRIP_LVC1_N")
		)
		(pad "D15" smd circle
			(at 5.199888 -3.599942 180)
			(size 0.4064 0.4064)
			(layers "F.Cu" "F.Mask" "F.Paste")
			(net "SMB_BMC_ALERT4_R1_N")
		)
		(pad "D16" smd circle
			(at 5.999988 -3.599942 180)
			(size 0.4064 0.4064)
			(layers "F.Cu" "F.Mask" "F.Paste")
			(net "H_CPU1_MEMTRIP_LVC1_N")
		)
		(pad "E1" smd circle
			(at -5.999988 -2.800096 180)
			(size 0.4064 0.4064)
			(layers "F.Cu" "F.Mask" "F.Paste")
			(net "Net_304")
		)
		(pad "E2" smd circle
			(at -5.199888 -2.800096 180)
			(size 0.4064 0.4064)
			(layers "F.Cu" "F.Mask" "F.Paste")
			(net "Net_300")
		)
		(pad "E3" smd circle
			(at -4.400042 -2.800096 180)
			(size 0.4064 0.4064)
			(layers "F.Cu" "F.Mask" "F.Paste")
			(net "Net_301")
		)
		(pad "E4" smd circle
			(at -3.599942 -2.800096 180)
			(size 0.4064 0.4064)
			(layers "F.Cu" "F.Mask" "F.Paste")
			(net "VCCIO5")
		)
		(pad "E5" smd circle
			(at -2.800096 -2.800096 180)
			(size 0.4064 0.4064)
			(layers "F.Cu" "F.Mask" "F.Paste")
			(net "GND")
		)
		(pad "E6" smd circle
			(at -1.999996 -2.800096 180)
			(size 0.4064 0.4064)
			(layers "F.Cu" "F.Mask" "F.Paste")
			(net "BMC_CPLD_GPIO_2_R2")
		)
		(pad "E7" smd circle
			(at -1.199896 -2.800096 180)
			(size 0.4064 0.4064)
			(layers "F.Cu" "F.Mask" "F.Paste")
			(net "PWRGD_PCH_PWROK")
		)
		(pad "E8" smd circle
			(at -0.40005 -2.800096 180)
			(size 0.4064 0.4064)
			(layers "F.Cu" "F.Mask" "F.Paste")
			(net "FM_BIOS_POST_CMPLT_BMC_N")
		)
		(pad "E9" smd circle
			(at 0.40005 -2.800096 180)
			(size 0.4064 0.4064)
			(layers "F.Cu" "F.Mask" "F.Paste")
			(net "H_CPU1_PROCHOT_LVC1_R_N")
		)
		(pad "E10" smd circle
			(at 1.199896 -2.800096 180)
			(size 0.4064 0.4064)
			(layers "F.Cu" "F.Mask" "F.Paste")
			(net "FM_CPU_MSMI_CATERR_LVT3_PLD_N")
		)
		(pad "E11" smd circle
			(at 1.999996 -2.800096 180)
			(size 0.4064 0.4064)
			(layers "F.Cu" "F.Mask" "F.Paste")
			(net "TP_PLD_19D")
		)
		(pad "E12" smd circle
			(at 2.800096 -2.800096 180)
			(size 0.4064 0.4064)
			(layers "F.Cu" "F.Mask" "F.Paste")
			(net "GND")
		)
		(pad "E13" smd circle
			(at 3.599942 -2.800096 180)
			(size 0.4064 0.4064)
			(layers "F.Cu" "F.Mask" "F.Paste")
			(net "VCCIO1")
		)
		(pad "E14" smd circle
			(at 4.400042 -2.800096 180)
			(size 0.4064 0.4064)
			(layers "F.Cu" "F.Mask" "F.Paste")
			(net "IRQ_SGPIO_R_N")
		)
		(pad "E15" smd circle
			(at 5.199888 -2.800096 180)
			(size 0.4064 0.4064)
			(layers "F.Cu" "F.Mask" "F.Paste")
			(net "FM_SPD_REMOTE_EN_R")
		)
		(pad "E16" smd circle
			(at 5.999988 -2.800096 180)
			(size 0.4064 0.4064)
			(layers "F.Cu" "F.Mask" "F.Paste")
			(net "RST_SGPIO_RESET_R_N")
		)
		(pad "F1" smd circle
			(at -5.999988 -1.999996 180)
			(size 0.4064 0.4064)
			(layers "F.Cu" "F.Mask" "F.Paste")
			(net "Net_309")
		)
		(pad "F2" smd circle
			(at -5.199888 -1.999996 180)
			(size 0.4064 0.4064)
			(layers "F.Cu" "F.Mask" "F.Paste")
			(net "Net_305")
		)
		(pad "F3" smd circle
			(at -4.400042 -1.999996 180)
			(size 0.4064 0.4064)
			(layers "F.Cu" "F.Mask" "F.Paste")
			(net "Net_308")
		)
		(pad "F4" smd circle
			(at -3.599942 -1.999996 180)
			(size 0.4064 0.4064)
			(layers "F.Cu" "F.Mask" "F.Paste")
			(net "Net_306")
		)
		(pad "F5" smd circle
			(at -2.800096 -1.999996 180)
			(size 0.4064 0.4064)
			(layers "F.Cu" "F.Mask" "F.Paste")
			(net "Net_314")
		)
		(pad "F6" smd circle
			(at -1.999996 -1.999996 180)
			(size 0.4064 0.4064)
			(layers "F.Cu" "F.Mask" "F.Paste")
			(net "GND")
		)
		(pad "F7" smd circle
			(at -1.199896 -1.999996 180)
			(size 0.4064 0.4064)
			(layers "F.Cu" "F.Mask" "F.Paste")
			(net "FM_PCIE_M2_SSD0_PRSNT_N")
		)
		(pad "F8" smd circle
			(at -0.40005 -1.999996 180)
			(size 0.4064 0.4064)
			(layers "F.Cu" "F.Mask" "F.Paste")
			(net "RST_SRST_PLD_BMC_R2_N")
		)
		(pad "F9" smd circle
			(at 0.40005 -1.999996 180)
			(size 0.4064 0.4064)
			(layers "F.Cu" "F.Mask" "F.Paste")
			(net "Net_76")
		)
		(pad "F10" smd circle
			(at 1.199896 -1.999996 180)
			(size 0.4064 0.4064)
			(layers "F.Cu" "F.Mask" "F.Paste")
			(net "IRQ_CPU0_VRHOT_N")
		)
		(pad "F11" smd circle
			(at 1.999996 -1.999996 180)
			(size 0.4064 0.4064)
			(layers "F.Cu" "F.Mask" "F.Paste")
			(net "GND")
		)
		(pad "F12" smd circle
			(at 2.800096 -1.999996 180)
			(size 0.4064 0.4064)
			(layers "F.Cu" "F.Mask" "F.Paste")
			(net "TP_PLD_L3")
		)
	)
)
